# S9S_MB_2U (Grand Teton) — schematic netlist excerpt (pin names and nets, part order shuffled) for the footprints in the layout excerpt that follows; sources: Cadence DE-HDL packaged netlist, KiCad conversion of 03242023_DA0F0TMBIJ0_F0T_Motherboard_J_brd_V01_OCP.brd

R1131  Q_RES  33.2 1% CHIP  pkg 0402LF  page 158 : A = SMB_PEHPCPU0_LVC3_SDA ; B = SMB_PEHPCPU0_LVC3_R_SDA
R2222  Q_RES  1K 1% CHIP  pkg 0402LF  page 306 : A = A_P12V_STBY_FP_TRIGGER ; B = GND

(kicad_pcb
	(version 20260206)
	(generator "pcbnew")
	(generator_version "10.0")
	(general
		(thickness 1.6)
		(legacy_teardrops no)
	)
	(paper "A4")
	(title_block
		(title "03242023_DA0F0TMBIJ0_F0T_Motherboard_J_brd_V01_OCP.brd")
		(comment 1 "Grand Teton / footprints 1460-1461 of 6105")
	)
	(layers
		(0 "F.Cu" signal "TOP")
		(4 "In1.Cu" signal "GND")
		(6 "In2.Cu" signal "IN1")
		(8 "In3.Cu" signal "GND1")
		(10 "In4.Cu" signal "IN2")
		(12 "In5.Cu" signal "GND2")
		(14 "In6.Cu" signal "IN3")
		(16 "In7.Cu" signal "GND3")
		(18 "In8.Cu" signal "VCC")
		(20 "In9.Cu" signal "VCC1")
		(22 "In10.Cu" signal "GND4")
		(24 "In11.Cu" signal "IN4")
		(26 "In12.Cu" signal "GND5")
		(28 "In13.Cu" signal "IN5")
		(30 "In14.Cu" signal "GND6")
		(32 "In15.Cu" signal "IN6")
		(34 "In16.Cu" signal "GND7")
		(2 "B.Cu" signal "BOTTOM")
		(9 "F.Adhes" user "F.Adhesive")
		(11 "B.Adhes" user "B.Adhesive")
		(13 "F.Paste" user "Package Geometry/Pastemask Top")
		(15 "B.Paste" user "Package Geometry/Pastemask Bottom")
		(5 "F.SilkS" user "Ref Des/Silkscreen Top")
		(7 "B.SilkS" user "Ref Des/Silkscreen Bottom")
		(1 "F.Mask" user "Board Geometry/Soldermask Top")
		(3 "B.Mask" user "Board Geometry/Soldermask Bottom")
		(17 "Dwgs.User" user "User.Drawings")
		(19 "Cmts.User" user "User.Comments")
		(21 "Eco1.User" user "User.Eco1")
		(23 "Eco2.User" user "User.Eco2")
		(25 "Edge.Cuts" user "Board Geometry/Outline")
		(27 "Margin" user)
		(31 "F.CrtYd" user "Package Geometry/Place Bound Top")
		(29 "B.CrtYd" user "Package Geometry/Place Bound Bottom")
		(35 "F.Fab" user "Ref Des/Assembly Top")
		(33 "B.Fab" user "Ref Des/Assembly Bottom")
	)
	(footprint ""
		(layer "F.Cu")
		(at 465.821014 -118.699534 180)
		(property "Reference" "R1131"
			(at 0 0 180)
			(layer "F.SilkS")
			(hide yes)
			(effects
				(font
					(size 1.27 1.27)
				)
			)
		)
		(property "Value" ""
			(at 0 0 180)
			(layer "F.Fab")
			(effects
				(font
					(size 1.27 1.27)
				)
			)
		)
		(duplicate_pad_numbers_are_jumpers no)
		(fp_line
			(start 0.7874 0.4064)
			(end -0.7874 0.4064)
			(stroke
				(width 0.1524)
				(type default)
			)
			(layer "F.SilkS")
		)
		(fp_line
			(start 0.7874 -0.4064)
			(end 0.7874 0.4064)
			(stroke
				(width 0.1524)
				(type default)
			)
			(layer "F.SilkS")
		)
		(fp_line
			(start -0.7874 0.4064)
			(end -0.7874 -0.4064)
			(stroke
				(width 0.1524)
				(type default)
			)
			(layer "F.SilkS")
		)
		(fp_line
			(start -0.7874 -0.4064)
			(end 0.7874 -0.4064)
			(stroke
				(width 0.1524)
				(type default)
			)
			(layer "F.SilkS")
		)
		(fp_line
			(start 0.67945 0.3048)
			(end 0.120396 0.3048)
			(stroke
				(width 0.1)
				(type default)
			)
			(layer "F.Fab")
		)
		(fp_line
			(start 0.67945 -0.3048)
			(end 0.67945 0.3048)
			(stroke
				(width 0.1)
				(type default)
			)
			(layer "F.Fab")
		)
		(fp_line
			(start 0.12065 -0.2794)
			(end 0.12065 -0.3048)
			(stroke
				(width 0.1)
				(type default)
			)
			(layer "F.Fab")
		)
		(fp_line
			(start 0.12065 -0.3048)
			(end 0.67945 -0.3048)
			(stroke
				(width 0.1)
				(type default)
			)
			(layer "F.Fab")
		)
		(fp_line
			(start 0.120396 0.3048)
			(end 0.120396 0.2794)
			(stroke
				(width 0.1)
				(type default)
			)
			(layer "F.Fab")
		)
		(fp_line
			(start 0.120396 0.2794)
			(end -0.12065 0.2794)
			(stroke
				(width 0.1)
				(type default)
			)
			(layer "F.Fab")
		)
		(fp_line
			(start -0.12065 0.3048)
			(end -0.67945 0.3048)
			(stroke
				(width 0.1)
				(type default)
			)
			(layer "F.Fab")
		)
		(fp_line
			(start -0.12065 0.2794)
			(end -0.12065 0.3048)
			(stroke
				(width 0.1)
				(type default)
			)
			(layer "F.Fab")
		)
		(fp_line
			(start -0.12065 -0.2794)
			(end 0.12065 -0.2794)
			(stroke
				(width 0.1)
				(type default)
			)
			(layer "F.Fab")
		)
		(fp_line
			(start -0.12065 -0.305054)
			(end -0.12065 -0.2794)
			(stroke
				(width 0.1)
				(type default)
			)
			(layer "F.Fab")
		)
		(fp_line
			(start -0.67945 0.3048)
			(end -0.67945 -0.305054)
			(stroke
				(width 0.1)
				(type default)
			)
			(layer "F.Fab")
		)
		(fp_line
			(start -0.67945 -0.305054)
			(end -0.12065 -0.305054)
			(stroke
				(width 0.1)
				(type default)
			)
			(layer "F.Fab")
		)
		(pad "1" smd circle
			(at -0.40005 0 180)
			(size 0 0)
			(layers "F.Cu" "F.Mask" "F.Paste")
			(net "SMB_PEHPCPU0_LVC3_SDA")
		)
		(pad "2" smd circle
			(at 0.40005 0 180)
			(size 0 0)
			(layers "F.Cu" "F.Mask" "F.Paste")
			(net "SMB_PEHPCPU0_LVC3_R_SDA")
		)
	)
	(footprint ""
		(layer "F.Cu")
		(at 220.087444 -97.13341)
		(property "Reference" "R2222"
			(at 0 0 0)
			(layer "F.SilkS")
			(hide yes)
			(effects
				(font
					(size 1.27 1.27)
				)
			)
		)
		(property "Value" ""
			(at 0 0 0)
			(layer "F.Fab")
			(effects
				(font
					(size 1.27 1.27)
				)
			)
		)
		(duplicate_pad_numbers_are_jumpers no)
		(fp_line
			(start -0.7874 -0.4064)
			(end 0.7874 -0.4064)
			(stroke
				(width 0.1524)
				(type default)
			)
			(layer "F.SilkS")
		)
		(fp_line
			(start -0.7874 0.4064)
			(end -0.7874 -0.4064)
			(stroke
				(width 0.1524)
				(type default)
			)
			(layer "F.SilkS")
		)
		(fp_line
			(start 0.7874 -0.4064)
			(end 0.7874 0.4064)
			(stroke
				(width 0.1524)
				(type default)
			)
			(layer "F.SilkS")
		)
		(fp_line
			(start 0.7874 0.4064)
			(end -0.7874 0.4064)
			(stroke
				(width 0.1524)
				(type default)
			)
			(layer "F.SilkS")
		)
		(fp_line
			(start -0.67945 -0.305054)
			(end -0.12065 -0.305054)
			(stroke
				(width 0.1)
				(type default)
			)
			(layer "F.Fab")
		)
		(fp_line
			(start -0.67945 0.3048)
			(end -0.67945 -0.305054)
			(stroke
				(width 0.1)
				(type default)
			)
			(layer "F.Fab")
		)
		(fp_line
			(start -0.12065 -0.305054)
			(end -0.12065 -0.2794)
			(stroke
				(width 0.1)
				(type default)
			)
			(layer "F.Fab")
		)
		(fp_line
			(start -0.12065 -0.2794)
			(end 0.12065 -0.2794)
			(stroke
				(width 0.1)
				(type default)
			)
			(layer "F.Fab")
		)
		(fp_line
			(start -0.12065 0.2794)
			(end -0.12065 0.3048)
			(stroke
				(width 0.1)
				(type default)
			)
			(layer "F.Fab")
		)
		(fp_line
			(start -0.12065 0.3048)
			(end -0.67945 0.3048)
			(stroke
				(width 0.1)
				(type default)
			)
			(layer "F.Fab")
		)
		(fp_line
			(start 0.120396 0.2794)
			(end -0.12065 0.2794)
			(stroke
				(width 0.1)
				(type default)
			)
			(layer "F.Fab")
		)
		(fp_line
			(start 0.120396 0.3048)
			(end 0.120396 0.2794)
			(stroke
				(width 0.1)
				(type default)
			)
			(layer "F.Fab")
		)
		(fp_line
			(start 0.12065 -0.3048)
			(end 0.67945 -0.3048)
			(stroke
				(width 0.1)
				(type default)
			)
			(layer "F.Fab")
		)
		(fp_line
			(start 0.12065 -0.2794)
			(end 0.12065 -0.3048)
			(stroke
				(width 0.1)
				(type default)
			)
			(layer "F.Fab")
		)
		(fp_line
			(start 0.67945 -0.3048)
			(end 0.67945 0.3048)
			(stroke
				(width 0.1)
				(type default)
			)
			(layer "F.Fab")
		)
		(fp_line
			(start 0.67945 0.3048)
			(end 0.120396 0.3048)
			(stroke
				(width 0.1)
				(type default)
			)
			(layer "F.Fab")
		)
		(pad "1" smd circle
			(at -0.40005 0)
			(size 0 0)
			(layers "F.Cu" "F.Mask" "F.Paste")
			(net "A_P12V_STBY_FP_TRIGGER")
		)
		(pad "2" smd circle
			(at 0.40005 0)
			(size 0 0)
			(layers "F.Cu" "F.Mask" "F.Paste")
			(net "GND")
		)
	)
)
